G04 ================== begin FILE IDENTIFICATION RECORD ==================*
G04 Layout Name:  17301-sa.brd*
G04 Film Name:    L6*
G04 File Format:  Gerber RS274X*
G04 File Origin:  Cadence Allegro 16.6-2015-S079*
G04 Origin Date:  Thu Jun 22 17:50:06 2017*
G04 *
G04 Layer:  VIA CLASS/BOTTOM*
G04 Layer:  PIN/BOTTOM*
G04 Layer:  ETCH/BOTTOM*
G04 Layer:  DRAWING FORMAT/LAYER_PCB_STORY*
G04 Layer:  DRAWING FORMAT/LAYER_L6*
G04 *
G04 Offset:    (0.00 0.00)*
G04 Mirror:    No*
G04 Mode:      Positive*
G04 Rotation:  0*
G04 FullContactRelief:  No*
G04 UndefLineWidth:     6.00*
G04 ================== end FILE IDENTIFICATION RECORD ====================*
%FSLAX35Y35*MOIN*%
%IR0*IPPOS*OFA0.00000B0.00000*MIA0B0*SFA1.00000B1.00000*%
%AMMACRO24*
4,1,40,.011,.007,
.011,-.007,
.010939,-.007695,
.010759,-.008368,
.010464,-.009,
.010064,-.009571,
.009571,-.010064,
.009,-.010464,
.008368,-.010759,
.007695,-.010939,
.007,-.011,
-.007,-.011,
-.007695,-.010939,
-.008368,-.010759,
-.009,-.010464,
-.009571,-.010064,
-.010064,-.009571,
-.010464,-.009,
-.010759,-.008368,
-.010939,-.007695,
-.011,-.007,
-.011,.007,
-.010939,.007695,
-.010759,.008368,
-.010464,.009,
-.010064,.009571,
-.009571,.010064,
-.009,.010464,
-.008368,.010759,
-.007695,.010939,
-.007,.011,
.007,.011,
.007695,.010939,
.008368,.010759,
.009,.010464,
.009571,.010064,
.010064,.009571,
.010464,.009,
.010759,.008368,
.010939,.007695,
.011,.007,
0.0*
%
%ADD24MACRO24*%
%AMMACRO38*
4,1,40,.013,-.017,
-.013,-.017,
-.013695,-.016939,
-.014368,-.016759,
-.015,-.016464,
-.015571,-.016064,
-.016064,-.015571,
-.016464,-.015,
-.016759,-.014368,
-.016939,-.013695,
-.017,-.013,
-.017,.013,
-.016939,.013695,
-.016759,.014368,
-.016464,.015,
-.016064,.015571,
-.015571,.016064,
-.015,.016464,
-.014368,.016759,
-.013695,.016939,
-.013,.017,
.013,.017,
.013695,.016939,
.014368,.016759,
.015,.016464,
.015571,.016064,
.016064,.015571,
.016464,.015,
.016759,.014368,
.016939,.013695,
.017,.013,
.017,-.013,
.016939,-.013695,
.016759,-.014368,
.016464,-.015,
.016064,-.015571,
.015571,-.016064,
.015,-.016464,
.014368,-.016759,
.013695,-.016939,
.013,-.017,
0.0*
%
%ADD38MACRO38*%
%ADD10C,.01*%
%ADD17C,.02*%
%ADD13C,.04*%
%ADD12C,.022*%
%ADD18C,.034*%
%ADD42C,.071*%
%ADD19C,.028*%
%ADD15C,.093*%
%AMMACRO29*
4,1,44,.023,.00387,
.022901,.005261,
.022562,.006614,
.021993,.007887,
.021211,.009042,
.020241,.010044,
.019112,.010863,
.017857,.011472,
.016516,.011855,
.015129,.011999,
.015,.012,
-.015,.012,
-.016389,.011878,
-.017737,.011517,
-.019001,.010928,
-.020143,.010128,
-.021129,.009142,
-.021929,.007999,
-.022519,.006735,
-.022879,.005388,
-.023001,.003999,
-.023,.00387,
-.023,-.00387,
-.022901,-.005261,
-.022562,-.006614,
-.021993,-.007887,
-.021211,-.009042,
-.020241,-.010044,
-.019112,-.010863,
-.017857,-.011472,
-.016516,-.011855,
-.015129,-.011999,
-.015,-.012,
.015,-.012,
.016389,-.011878,
.017737,-.011517,
.019001,-.010928,
.020143,-.010128,
.021129,-.009142,
.021929,-.007999,
.022519,-.006735,
.022879,-.005388,
.023001,-.003999,
.023,-.00387,
.023,.00387,
0.0*
%
%ADD29MACRO29*%
%AMMACRO41*
4,1,40,-.012,-.008,
-.012,.008,
-.011939,.008695,
-.011759,.009368,
-.011464,.01,
-.011064,.010571,
-.010571,.011064,
-.01,.011464,
-.009368,.011759,
-.008695,.011939,
-.008,.012,
.008,.012,
.008695,.011939,
.009368,.011759,
.01,.011464,
.010571,.011064,
.011064,.010571,
.011464,.01,
.011759,.009368,
.011939,.008695,
.012,.008,
.012,-.008,
.011939,-.008695,
.011759,-.009368,
.011464,-.01,
.011064,-.010571,
.010571,-.011064,
.01,-.011464,
.009368,-.011759,
.008695,-.011939,
.008,-.012,
-.008,-.012,
-.008695,-.011939,
-.009368,-.011759,
-.01,-.011464,
-.010571,-.011064,
-.011064,-.010571,
-.011464,-.01,
-.011759,-.009368,
-.011939,-.008695,
-.012,-.008,
0.0*
%
%ADD41MACRO41*%
%AMMACRO27*
4,1,40,-.013,.017,
.013,.017,
.013695,.016939,
.014368,.016759,
.015,.016464,
.015571,.016064,
.016064,.015571,
.016464,.015,
.016759,.014368,
.016939,.013695,
.017,.013,
.017,-.013,
.016939,-.013695,
.016759,-.014368,
.016464,-.015,
.016064,-.015571,
.015571,-.016064,
.015,-.016464,
.014368,-.016759,
.013695,-.016939,
.013,-.017,
-.013,-.017,
-.013695,-.016939,
-.014368,-.016759,
-.015,-.016464,
-.015571,-.016064,
-.016064,-.015571,
-.016464,-.015,
-.016759,-.014368,
-.016939,-.013695,
-.017,-.013,
-.017,.013,
-.016939,.013695,
-.016759,.014368,
-.016464,.015,
-.016064,.015571,
-.015571,.016064,
-.015,.016464,
-.014368,.016759,
-.013695,.016939,
-.013,.017,
0.0*
%
%ADD27MACRO27*%
%AMMACRO40*
4,1,40,-.012,-.008,
-.012,.008,
-.011939,.008695,
-.011759,.009368,
-.011464,.01,
-.011064,.010571,
-.010571,.011064,
-.01,.011464,
-.009368,.011759,
-.008695,.011939,
-.008,.012,
.008,.012,
.008695,.011939,
.009368,.011759,
.01,.011464,
.010571,.011064,
.011064,.010571,
.011464,.01,
.011759,.009368,
.011939,.008695,
.012,.008,
.012,-.008,
.011939,-.008695,
.011759,-.009368,
.011464,-.01,
.011064,-.010571,
.010571,-.011064,
.01,-.011464,
.009368,-.011759,
.008695,-.011939,
.008,-.012,
-.008,-.012,
-.008695,-.011939,
-.009368,-.011759,
-.01,-.011464,
-.010571,-.011064,
-.011064,-.010571,
-.011464,-.01,
-.011759,-.009368,
-.011939,-.008695,
-.012,-.008,
0.0*
%
%ADD40MACRO40*%
%AMMACRO28*
4,1,40,-.013,.017,
.013,.017,
.013695,.016939,
.014368,.016759,
.015,.016464,
.015571,.016064,
.016064,.015571,
.016464,.015,
.016759,.014368,
.016939,.013695,
.017,.013,
.017,-.013,
.016939,-.013695,
.016759,-.014368,
.016464,-.015,
.016064,-.015571,
.015571,-.016064,
.015,-.016464,
.014368,-.016759,
.013695,-.016939,
.013,-.017,
-.013,-.017,
-.013695,-.016939,
-.014368,-.016759,
-.015,-.016464,
-.015571,-.016064,
-.016064,-.015571,
-.016464,-.015,
-.016759,-.014368,
-.016939,-.013695,
-.017,-.013,
-.017,.013,
-.016939,.013695,
-.016759,.014368,
-.016464,.015,
-.016064,.015571,
-.015571,.016064,
-.015,.016464,
-.014368,.016759,
-.013695,.016939,
-.013,.017,
0.0*
%
%ADD28MACRO28*%
%ADD39R,.04X.022*%
%ADD20O,.024X.032*%
%ADD36R,.016X.04*%
%ADD14R,.071X.032*%
%ADD16R,.063X.024*%
%ADD32R,.05X.065*%
%ADD30R,.047X.014*%
%ADD22R,.065X.025*%
%ADD43R,.045X.055*%
%ADD35R,.016X.048*%
%ADD11C,.237*%
%ADD31O,.086X.048*%
%AMMACRO21*
4,1,40,-.007,.0225,
-.008389,.022378,
-.009736,.022018,
-.011,.021428,
-.012142,.020628,
-.013128,.019642,
-.013928,.0185,
-.014518,.017236,
-.014878,.015889,
-.015,.0145,
-.015,-.0145,
-.014878,-.015889,
-.014518,-.017236,
-.013928,-.0185,
-.013128,-.019642,
-.012142,-.020628,
-.011,-.021428,
-.009736,-.022018,
-.008389,-.022378,
-.007,-.0225,
.007,-.0225,
.008389,-.022378,
.009736,-.022018,
.011,-.021428,
.012142,-.020628,
.013128,-.019642,
.013928,-.0185,
.014518,-.017236,
.014878,-.015889,
.015,-.0145,
.015,.0145,
.014878,.015889,
.014518,.017236,
.013928,.0185,
.013128,.019642,
.012142,.020628,
.011,.021428,
.009736,.022018,
.008389,.022378,
.007,.0225,
-.007,.0225,
0.0*
%
%ADD21MACRO21*%
%AMMACRO34*
4,1,40,.012,.008,
.012,-.008,
.011939,-.008695,
.011759,-.009368,
.011464,-.01,
.011064,-.010571,
.010571,-.011064,
.01,-.011464,
.009368,-.011759,
.008695,-.011939,
.008,-.012,
-.008,-.012,
-.008695,-.011939,
-.009368,-.011759,
-.01,-.011464,
-.010571,-.011064,
-.011064,-.010571,
-.011464,-.01,
-.011759,-.009368,
-.011939,-.008695,
-.012,-.008,
-.012,.008,
-.011939,.008695,
-.011759,.009368,
-.011464,.01,
-.011064,.010571,
-.010571,.011064,
-.01,.011464,
-.009368,.011759,
-.008695,.011939,
-.008,.012,
.008,.012,
.008695,.011939,
.009368,.011759,
.01,.011464,
.010571,.011064,
.011064,.010571,
.011464,.01,
.011759,.009368,
.011939,.008695,
.012,.008,
0.0*
%
%ADD34MACRO34*%
%AMMACRO26*
4,1,40,.008,-.012,
-.008,-.012,
-.008695,-.011939,
-.009368,-.011759,
-.01,-.011464,
-.010571,-.011064,
-.011064,-.010571,
-.011464,-.01,
-.011759,-.009368,
-.011939,-.008695,
-.012,-.008,
-.012,.008,
-.011939,.008695,
-.011759,.009368,
-.011464,.01,
-.011064,.010571,
-.010571,.011064,
-.01,.011464,
-.009368,.011759,
-.008695,.011939,
-.008,.012,
.008,.012,
.008695,.011939,
.009368,.011759,
.01,.011464,
.010571,.011064,
.011064,.010571,
.011464,.01,
.011759,.009368,
.011939,.008695,
.012,.008,
.012,-.008,
.011939,-.008695,
.011759,-.009368,
.011464,-.01,
.011064,-.010571,
.010571,-.011064,
.01,-.011464,
.009368,-.011759,
.008695,-.011939,
.008,-.012,
0.0*
%
%ADD26MACRO26*%
%AMMACRO23*
4,1,40,.011,.007,
.011,-.007,
.010939,-.007695,
.010759,-.008368,
.010464,-.009,
.010064,-.009571,
.009571,-.010064,
.009,-.010464,
.008368,-.010759,
.007695,-.010939,
.007,-.011,
-.007,-.011,
-.007695,-.010939,
-.008368,-.010759,
-.009,-.010464,
-.009571,-.010064,
-.010064,-.009571,
-.010464,-.009,
-.010759,-.008368,
-.010939,-.007695,
-.011,-.007,
-.011,.007,
-.010939,.007695,
-.010759,.008368,
-.010464,.009,
-.010064,.009571,
-.009571,.010064,
-.009,.010464,
-.008368,.010759,
-.007695,.010939,
-.007,.011,
.007,.011,
.007695,.010939,
.008368,.010759,
.009,.010464,
.009571,.010064,
.010064,.009571,
.010464,.009,
.010759,.008368,
.010939,.007695,
.011,.007,
0.0*
%
%ADD23MACRO23*%
%AMMACRO37*
4,1,40,.013,-.017,
-.013,-.017,
-.013695,-.016939,
-.014368,-.016759,
-.015,-.016464,
-.015571,-.016064,
-.016064,-.015571,
-.016464,-.015,
-.016759,-.014368,
-.016939,-.013695,
-.017,-.013,
-.017,.013,
-.016939,.013695,
-.016759,.014368,
-.016464,.015,
-.016064,.015571,
-.015571,.016064,
-.015,.016464,
-.014368,.016759,
-.013695,.016939,
-.013,.017,
.013,.017,
.013695,.016939,
.014368,.016759,
.015,.016464,
.015571,.016064,
.016064,.015571,
.016464,.015,
.016759,.014368,
.016939,.013695,
.017,.013,
.017,-.013,
.016939,-.013695,
.016759,-.014368,
.016464,-.015,
.016064,-.015571,
.015571,-.016064,
.015,-.016464,
.014368,-.016759,
.013695,-.016939,
.013,-.017,
0.0*
%
%ADD37MACRO37*%
%AMMACRO33*
4,1,40,.012,.008,
.012,-.008,
.011939,-.008695,
.011759,-.009368,
.011464,-.01,
.011064,-.010571,
.010571,-.011064,
.01,-.011464,
.009368,-.011759,
.008695,-.011939,
.008,-.012,
-.008,-.012,
-.008695,-.011939,
-.009368,-.011759,
-.01,-.011464,
-.010571,-.011064,
-.011064,-.010571,
-.011464,-.01,
-.011759,-.009368,
-.011939,-.008695,
-.012,-.008,
-.012,.008,
-.011939,.008695,
-.011759,.009368,
-.011464,.01,
-.011064,.010571,
-.010571,.011064,
-.01,.011464,
-.009368,.011759,
-.008695,.011939,
-.008,.012,
.008,.012,
.008695,.011939,
.009368,.011759,
.01,.011464,
.010571,.011064,
.011064,.010571,
.011464,.01,
.011759,.009368,
.011939,.008695,
.012,.008,
0.0*
%
%ADD33MACRO33*%
%AMMACRO25*
4,1,40,.008,-.012,
-.008,-.012,
-.008695,-.011939,
-.009368,-.011759,
-.01,-.011464,
-.010571,-.011064,
-.011064,-.010571,
-.011464,-.01,
-.011759,-.009368,
-.011939,-.008695,
-.012,-.008,
-.012,.008,
-.011939,.008695,
-.011759,.009368,
-.011464,.01,
-.011064,.010571,
-.010571,.011064,
-.01,.011464,
-.009368,.011759,
-.008695,.011939,
-.008,.012,
.008,.012,
.008695,.011939,
.009368,.011759,
.01,.011464,
.010571,.011064,
.011064,.010571,
.011464,.01,
.011759,.009368,
.011939,.008695,
.012,.008,
.012,-.008,
.011939,-.008695,
.011759,-.009368,
.011464,-.01,
.011064,-.010571,
.010571,-.011064,
.01,-.011464,
.009368,-.011759,
.008695,-.011939,
.008,-.012,
0.0*
%
%ADD25MACRO25*%
%ADD44C,.012*%
%ADD45C,.015*%
%ADD46C,.006*%
%ADD47C,.0072*%
%ADD48C,.0084*%
%ADD49C,.09204*%
%ADD50C,.11004*%
%ADD51R,.008X.008*%
G75*
%LPD*%
G75*
G36*
G01X3001Y87402D02*
G02X3937Y88338I936J0D01*
G01X48328D01*
X48333Y88333D01*
X64516D01*
X64521Y88338D01*
X191689D01*
Y86174D01*
X190581Y85066D01*
X71973D01*
X69365Y82458D01*
X67268D01*
X67263Y82463D01*
X65237D01*
X61091Y86609D01*
X51059D01*
X49479Y85029D01*
Y62083D01*
X50093Y61469D01*
X58251D01*
X58625Y61095D01*
Y51714D01*
X58150Y51239D01*
X50032D01*
X49130Y50337D01*
Y34750D01*
X49858Y34022D01*
X58033D01*
X58863Y33192D01*
Y4463D01*
X57401Y3001D01*
X3937D01*
G02X3001Y3937I0J936D01*
G01Y87402D01*
G37*
G36*
G01X61375Y78687D02*
X51559D01*
X51068Y79178D01*
Y84778D01*
X51584Y85294D01*
X60600D01*
X61640Y84254D01*
Y78952D01*
X61375Y78687D01*
G37*
G36*
G01X257784Y35210D02*
X256494Y36500D01*
Y52690D01*
X258061Y54257D01*
X270066D01*
X270821Y53502D01*
Y36788D01*
X269243Y35210D01*
X257784D01*
G37*
G36*
G01X316041Y26375D02*
X316843D01*
X320375Y22843D01*
Y14769D01*
X327144Y8000D01*
X345183D01*
X345240Y7830D01*
G03X348972Y6866I2181J738D01*
G01X357348D01*
X357928Y7447D01*
X358481Y8000D01*
X372980D01*
Y3937D01*
G02X372047Y3004I-933J0D01*
G01X294096D01*
X290550Y6550D01*
Y17550D01*
X297072Y24072D01*
X306800D01*
X308400Y25672D01*
Y29348D01*
X308462D01*
Y36552D01*
X308014Y37000D01*
X306302D01*
X305902Y37400D01*
Y44057D01*
X305500Y44459D01*
Y47600D01*
X306200Y48300D01*
X309100D01*
X310098Y47302D01*
Y45000D01*
G03X310099Y44956I1602J14D01*
G03X310100Y44936I1600J70D01*
G01Y43200D01*
X311650Y41650D01*
Y26158D01*
X312473Y25335D01*
X312727D01*
X312786Y25301D01*
G03X315841Y26160I1114J1899D01*
G01X315858Y26192D01*
X316041Y26375D01*
G37*
G36*
G01X291808Y40955D02*
X277872D01*
X276368Y42459D01*
Y55360D01*
X277752Y56744D01*
X282846D01*
X286493Y60391D01*
X289728D01*
X290192Y59927D01*
Y56744D01*
X293222Y53714D01*
Y42370D01*
X291808Y40955D01*
G37*
G36*
G01X285500Y144200D02*
X283600Y146100D01*
Y162900D01*
X287100Y166400D01*
X294000D01*
X294288Y166112D01*
Y145188D01*
X293300Y144200D01*
X285500D01*
G37*
G36*
G01X308955Y166045D02*
X321548D01*
X322446Y165147D01*
Y149896D01*
G02X321964Y149397I-500J1D01*
G03X320038Y148108I78J-2201D01*
G01X319971Y147962D01*
X308000D01*
X303338Y143300D01*
X297000D01*
X295500Y144800D01*
Y163936D01*
G03X295502Y164000I-1599J82D01*
G01Y165600D01*
G03X295500Y165664I-1601J-18D01*
G01Y166000D01*
X296500Y167000D01*
X308000D01*
X308955Y166045D01*
G37*
G36*
G01X537402Y3001D02*
G02X536466Y3937I0J936D01*
G01Y110310D01*
X532317Y114459D01*
X521168D01*
X521148Y114438D01*
X520180D01*
X517170Y111428D01*
Y108421D01*
X517166Y108417D01*
Y97803D01*
X513748Y94386D01*
Y89224D01*
G02X512804Y88994I-500J0D01*
G03Y84628I-4221J-2183D01*
G02X513748Y84398I444J-230D01*
G01Y81028D01*
X511932Y79212D01*
X493741D01*
X492019Y80934D01*
Y83728D01*
G02X492924Y84022I500J0D01*
G03Y89600I3847J2789D01*
G02X492019Y89894I-405J294D01*
G01Y93095D01*
X487807Y97307D01*
Y110621D01*
X487808Y110622D01*
Y124121D01*
X493044Y129357D01*
X506779D01*
X516588Y139166D01*
X516671Y139177D01*
G03X518710Y140123I-531J3815D01*
G02X519474Y140005I334J-373D01*
G03Y145979I5032J2987D01*
G02X518710Y145861I-430J255D01*
G03X517937Y146399I-2570J-2868D01*
G01Y205333D01*
G03X518710Y205871I-1797J3406D01*
G02X519474Y205753I334J-373D01*
G03Y211727I5032J2987D01*
G02X518710Y211609I-430J255D01*
G03X516271Y212589I-2569J-2869D01*
G01X516172Y212593D01*
X494410Y234355D01*
X476655D01*
X474700Y232400D01*
Y228550D01*
G03Y225950I1900J-1300D01*
G01Y222020D01*
X471200Y218520D01*
X444738D01*
X435851Y227407D01*
X433512D01*
X429765Y231154D01*
X321784D01*
X321423Y230793D01*
X299465D01*
X283112Y214440D01*
Y173318D01*
X281394Y171600D01*
X277626D01*
X276626Y172600D01*
Y210165D01*
X276623Y210168D01*
Y252756D01*
G02X277559Y253692I936J0D01*
G01X561024D01*
G02X561960Y252756I0J-936D01*
G01Y220289D01*
X561957Y220286D01*
Y72769D01*
X561960D01*
Y3937D01*
G02X561024Y3001I-936J0D01*
G01X537402D01*
G37*
G36*
G01X321141Y53744D02*
X320147Y54738D01*
Y57365D01*
X321115Y58333D01*
X330623D01*
X331160Y57796D01*
Y55670D01*
X330771Y55281D01*
X327832D01*
X325887Y53336D01*
Y50035D01*
X325597Y49745D01*
X321482D01*
X321144Y50083D01*
Y51719D01*
G03X321141Y51817I-1602J0D01*
G01Y53744D01*
G37*
G36*
G01X305324Y187014D02*
X304209Y188129D01*
Y203657D01*
X305463Y204911D01*
X319612D01*
X321122Y203401D01*
Y187752D01*
X320384Y187014D01*
X305324D01*
G37*
G36*
G01X341534Y35664D02*
X328016D01*
X327625Y36054D01*
X327168Y36511D01*
Y52889D01*
X328279Y54000D01*
X341500D01*
X341952Y53548D01*
Y36082D01*
X341534Y35664D01*
G37*
G36*
G01X342424Y153436D02*
X341934Y152946D01*
X324578D01*
X324078Y153446D01*
Y166251D01*
X325739Y167912D01*
X341448D01*
X342424Y166936D01*
Y153436D01*
G37*
G36*
G01X339500Y192000D02*
X324709D01*
X324209Y192500D01*
Y205305D01*
X325870Y206966D01*
X338971D01*
X341122Y204815D01*
Y193622D01*
X339500Y192000D01*
G37*
G36*
G01X361452Y40000D02*
X348125D01*
X347625Y40500D01*
Y53625D01*
X348500Y54500D01*
X360952D01*
X361952Y53500D01*
Y40500D01*
X361452Y40000D01*
G37*
G36*
G01X488861Y84097D02*
G02X489771Y83811I410J-286D01*
G01Y80255D01*
X488713Y79197D01*
X479147D01*
X477880Y80464D01*
Y108982D01*
X479901Y111003D01*
X485664D01*
X486510Y110156D01*
Y96731D01*
X489771Y93470D01*
Y89811D01*
G02X488861Y89525I-500J0D01*
G03Y84097I-3901J-2714D01*
G37*
G36*
G01X513469Y164342D02*
X511764Y162637D01*
X506718D01*
X505367Y163988D01*
Y200589D01*
X506291Y201513D01*
Y201597D01*
X506366Y201671D01*
G03X504707Y206618I-2035J2069D01*
G01X504622Y206629D01*
X503413Y207838D01*
X498350D01*
X479040Y227148D01*
Y231615D01*
X480218Y232793D01*
X490007D01*
X512581Y210219D01*
X512526Y210069D01*
G03X513469Y205966I3615J-1329D01*
G01Y164342D01*
G37*
G36*
G01X515934Y79024D02*
X515339Y79619D01*
Y84197D01*
G02X516273Y84446I500J0D01*
G03Y89176I4121J2365D01*
G02X515339Y89425I-434J249D01*
G01Y91861D01*
X518559Y95081D01*
Y110268D01*
X519974Y111683D01*
X531725D01*
X532593Y110815D01*
Y84924D01*
X526693Y79024D01*
X515934D01*
G37*
%LPC*%
G75*
G54D49*
X32739Y30456D03*
G54D50*
X17715Y44095D03*
X525590Y240944D03*
X552795Y40157D03*
G54D51*
X309100Y44600D03*
X286029Y56857D03*
X291900Y163600D03*
X297900D03*
Y166000D03*
X514797Y105578D03*
X490148Y105594D03*
X514797Y107978D03*
X490148Y107994D03*
X323543Y52119D03*
X484148Y107994D03*
Y105594D03*
X520797Y105578D03*
Y107978D03*
%LPD*%
G75*
G54D10*
G01X74635Y29153D02*
X67174Y36614D01*
X54724D01*
G01Y48425D02*
X63713D01*
G01X65006Y43434D02*
X63952Y44488D01*
X54724D01*
G01X75100Y36700D02*
X71249Y40551D01*
X54724D01*
G01X208000Y90000D02*
X205500Y92500D01*
X200924D01*
X191789Y83365D01*
X72678D01*
X65297Y75984D01*
X54724D01*
G01X204500Y90000D02*
X201816D01*
X192981Y81165D01*
X73590D01*
X64472Y72047D01*
X54724D01*
G01X76804Y61699D02*
X70393Y68110D01*
X54724D01*
G01Y64173D02*
X60928D01*
G01X261939Y10864D02*
X241992D01*
X237328Y6200D01*
X84800D01*
X83800Y7200D01*
Y34200D01*
X76804Y41196D01*
Y61699D01*
G01X188287Y10039D02*
X199632Y21384D01*
X250817D01*
X253353Y18848D01*
X261403D01*
G01X301340Y39450D02*
X297568D01*
X294391Y36273D01*
Y32474D01*
X289933Y28016D01*
Y23659D01*
X277138Y10864D01*
X261939D01*
G01X303900Y39450D02*
Y43036D01*
X302736Y44200D01*
X298142D01*
X292105Y38163D01*
Y33300D01*
X287733Y28928D01*
Y24571D01*
X277277Y14115D01*
X266136D01*
X261403Y18848D01*
G01X268346Y29819D02*
Y31907D01*
X273551Y37112D01*
G01X281083Y26478D02*
X279420D01*
X275261Y22319D01*
X272221D01*
G01D02*
Y31357D01*
X278364Y37500D01*
X287500D01*
G01X285083Y26478D02*
X281083D01*
G01X297578Y81023D02*
X293146D01*
G01X293529Y58557D02*
X306279D01*
X307544Y57292D01*
G01X293141Y97997D02*
X293884Y98740D01*
X297578D01*
G01X279500Y116900D02*
X277237Y119163D01*
Y165037D01*
X285998Y173798D01*
Y209354D01*
X292129Y215485D01*
G01X279437Y120731D02*
Y163737D01*
X288498Y172798D01*
Y207172D01*
G01X317440Y219750D02*
X311672D01*
X307407Y215485D01*
X292129D01*
G01X320000Y219750D02*
Y211039D01*
X318124Y209163D01*
X290489D01*
X288498Y207172D01*
G01X307544Y57292D02*
X308133Y56703D01*
X316624D01*
G01X313200Y46300D02*
X314900D01*
X316400Y44800D01*
Y40400D01*
G01X313840D02*
Y37182D01*
X314840Y36182D01*
X324251D01*
X328196Y32237D01*
G01X308208Y81023D02*
X313617D01*
G01X308208Y98740D02*
Y101945D01*
G01X321440Y101571D02*
X322106Y100905D01*
Y98740D01*
G01X309500Y133300D02*
Y127750D01*
X309250Y127500D01*
Y127439D01*
G01D02*
X307940D01*
X306940Y128439D01*
Y133300D01*
G01X309500Y140700D02*
Y145000D01*
G01X322042Y147196D02*
X319400Y144554D01*
Y141500D01*
G01X312060Y140700D02*
X314984D01*
X315784Y141500D01*
X319400D01*
G01X310500Y184328D02*
X305253D01*
X302291Y187290D01*
Y204145D01*
X304783Y206637D01*
X319204D01*
X322560Y209993D01*
Y213250D01*
G01X315354Y180444D02*
X314384D01*
X310500Y184328D01*
G01X319229Y172944D02*
X322569Y176284D01*
X328034D01*
G01X479331Y203740D02*
X469036Y214035D01*
X444478D01*
X429060Y229453D01*
X322489D01*
X317440Y224404D01*
Y219750D01*
G01X479331Y137992D02*
Y149222D01*
X493404Y163295D01*
Y183228D01*
X480115Y196517D01*
X428621D01*
X398173Y226965D01*
X324516D01*
X320000Y222449D01*
Y219750D01*
G01X340000Y20300D02*
Y14667D01*
G01D02*
X338440D01*
X337440Y15667D01*
Y20300D01*
G01X328196Y32237D02*
X339000D01*
X340000Y31237D01*
Y27700D01*
G01X324700Y16300D02*
X332311Y23911D01*
X339212D01*
X340000Y24699D01*
Y27700D01*
G01X342560D02*
X344200D01*
X345900Y29400D01*
X349900D01*
G01X326892Y79371D02*
X325240Y81023D01*
X322106D01*
G01X337406Y79575D02*
X335958Y81023D01*
X332736D01*
G01Y98740D02*
X338145D01*
G01X327057Y90943D02*
X325996Y89882D01*
X322106D01*
G01X337670Y90976D02*
X336576Y89882D01*
X332736D01*
G01X328400Y141500D02*
Y145321D01*
X329000Y145921D01*
Y149500D01*
G01X336238Y148951D02*
X335689Y149500D01*
X329000D01*
G01X329131Y188554D02*
X335931D01*
X337494Y186991D01*
Y177470D01*
G01X328034Y176284D02*
X328068Y176250D01*
X332000D01*
G01D02*
X336274D01*
X337494Y177470D01*
G01X347421Y8568D02*
X356643D01*
X372444Y24369D01*
Y97605D01*
X378183Y103344D01*
X461577D01*
X470551Y112318D01*
G01X350479Y10768D02*
X355731D01*
X370244Y25281D01*
Y98517D01*
X377271Y105544D01*
X451883D01*
X459514Y113175D01*
G01X351040Y34753D02*
X349900Y33613D01*
Y29400D01*
G01X358900D02*
Y23928D01*
G01X364750Y37750D02*
X364054Y37054D01*
X358631D01*
G01X484331Y203740D02*
Y196832D01*
X497330Y183833D01*
Y155594D01*
X509562Y143362D01*
Y136785D01*
X505657Y132880D01*
X491113D01*
X470551Y112318D01*
G01X484331Y137992D02*
X459514Y113175D01*
X-14755Y415558D03*
X-12454Y45507D03*
X17715Y44095D03*
X29461Y718854D03*
X141466Y655356D03*
X225097Y15039D03*
Y59528D03*
X312657Y66142D03*
Y107716D03*
X395935Y76695D03*
X473149Y79094D03*
X508569Y15093D03*
X516141Y142992D03*
Y208740D03*
X525590Y240944D03*
X552795Y40157D03*
X532205Y79094D03*
X554126Y315939D03*
Y685624D03*
G54D11*
X15748Y15827D03*
Y67008D03*
X303150Y13780D03*
Y242913D03*
X551181Y13780D03*
Y242913D03*
G54D20*
X140237Y23464D03*
X137087D03*
X133937D03*
X130787D03*
X127637D03*
X124487D03*
X121337D03*
X140237Y67953D03*
X137087D03*
X133937D03*
X130787D03*
X127637D03*
X124487D03*
X121337D03*
X412381Y151417D03*
Y217165D03*
X431281Y151417D03*
X428131D03*
X424981D03*
X421831D03*
X418681D03*
X415531D03*
X431281Y217165D03*
X428131D03*
X424981D03*
X421831D03*
X418681D03*
X415531D03*
G54D21*
X272221Y22319D03*
X268346Y29819D03*
X276096D03*
X319229Y172944D03*
X315354Y180444D03*
X323104D03*
G54D30*
X297578Y81023D03*
Y78071D03*
Y75118D03*
Y98740D03*
Y95787D03*
Y92835D03*
Y89882D03*
Y86929D03*
Y83976D03*
X322106Y81023D03*
Y78071D03*
Y75118D03*
X308208Y81023D03*
Y78071D03*
Y75118D03*
X322106Y98740D03*
Y95787D03*
Y92835D03*
Y89882D03*
Y86929D03*
Y83976D03*
X308208Y98740D03*
Y95787D03*
Y92835D03*
Y89882D03*
Y86929D03*
Y83976D03*
X332736Y81023D03*
Y78071D03*
Y75118D03*
Y98740D03*
Y95787D03*
Y92835D03*
Y89882D03*
Y86929D03*
Y83976D03*
G54D12*
X5500Y48299D03*
X7960Y85839D03*
X42701Y5500D03*
X48316Y32530D03*
X44316D03*
Y28681D03*
X48316D03*
X44278Y24717D03*
X48278D03*
X49374Y56390D03*
X45374D03*
X45336Y52426D03*
X49336D03*
X41000Y79500D03*
Y75500D03*
X37000Y79500D03*
Y75500D03*
X49374Y60239D03*
X45374D03*
X27960Y85839D03*
X63713Y48425D03*
X65006Y43434D03*
X60469Y79819D03*
X67960Y85839D03*
X56667Y83351D03*
X60393Y83934D03*
X52667Y83351D03*
X87960Y85839D03*
X107960D03*
X127960D03*
X147960D03*
X167960D03*
X207675Y38907D03*
X204000Y82000D03*
X208000D03*
Y86000D03*
X204000D03*
X187960Y85839D03*
X214906Y39494D03*
X211337Y38963D03*
X242500Y27000D03*
X246500D03*
X243000Y47500D03*
X247000D03*
X244727Y76591D03*
X244870Y80370D03*
X248866Y76464D03*
X248811Y80272D03*
X261719Y52314D03*
X261774Y48506D03*
X261840Y42259D03*
X261924Y38480D03*
X258240Y42259D03*
X258174Y48506D03*
X258119Y52314D03*
X258324Y38480D03*
X281221Y33971D03*
X286638Y33917D03*
X282148Y51376D03*
X282093Y55184D03*
X278462Y51437D03*
X278407Y55245D03*
X281964Y47752D03*
X278278Y47813D03*
X284292Y61505D03*
X280555Y61542D03*
X284798Y149063D03*
X299300Y144500D03*
X284905Y160541D03*
X284940Y156881D03*
X284798Y152687D03*
X289800Y165000D03*
X300000Y164900D03*
X297698Y191563D03*
Y195187D03*
X279122Y174213D03*
Y194213D03*
X297840Y199381D03*
X297805Y203041D03*
X279122Y214213D03*
Y234213D03*
X282142Y251193D03*
X322701Y5500D03*
X321373Y56703D03*
X303700Y140700D03*
X315048Y133300D03*
X302000Y133500D03*
X301913Y129821D03*
X303000Y144400D03*
X309500Y145000D03*
X303600Y164800D03*
X320332Y160022D03*
X316332D03*
Y164522D03*
X320332D03*
X316332Y155668D03*
X320332D03*
X316438Y151436D03*
X320438D03*
X318500Y193500D03*
X314500D03*
X318500Y188500D03*
X314500D03*
X300754Y205956D03*
X304000Y213000D03*
X314454Y213250D03*
X314500Y203500D03*
X318500D03*
Y198500D03*
X314500D03*
X322142Y251193D03*
X332666Y27700D03*
X332778Y20000D03*
X328508Y41629D03*
X328424Y45408D03*
X332508Y41629D03*
X332424Y45408D03*
X332565Y49028D03*
X332614Y52663D03*
X328565Y49028D03*
X328614Y52663D03*
X336698Y154738D03*
X340698D03*
X340779Y158381D03*
Y162024D03*
X336779D03*
Y158381D03*
X340779Y165718D03*
X336779D03*
X326423Y183632D03*
X332000Y183500D03*
X339000Y193500D03*
X335000D03*
X326000Y217500D03*
X335000Y203500D03*
X339000D03*
Y198500D03*
X335000D03*
X342142Y251193D03*
X357672Y4602D03*
X347421Y8568D03*
X350479Y10768D03*
X345690Y20300D03*
X353229Y52810D03*
X349229D03*
X353095Y45538D03*
X353094Y49157D03*
X352971Y41813D03*
X349095Y45538D03*
X349094Y49157D03*
X348971Y41813D03*
X364750Y37750D03*
X354580Y102351D03*
X350569Y102263D03*
X358824Y108849D03*
X352501Y105640D03*
X350827Y108976D03*
X348696Y105396D03*
X356501Y105640D03*
X354827Y108976D03*
X362142Y251193D03*
X382142D03*
X402142D03*
X422142D03*
X442142D03*
X471445Y93346D03*
X476600Y227250D03*
X480101Y230616D03*
X462142Y251193D03*
X502868Y166448D03*
X483700Y230522D03*
X502142Y251193D03*
X482142D03*
X519980Y226295D03*
X523642Y226351D03*
X520017Y230070D03*
X523642Y230014D03*
X522142Y251193D03*
X538965Y41992D03*
Y61992D03*
X559461Y68512D03*
Y88512D03*
Y108512D03*
Y148512D03*
Y128512D03*
Y168512D03*
Y188512D03*
Y208512D03*
G54D31*
X295472Y65571D03*
Y108287D03*
X330590Y65571D03*
Y108287D03*
G54D22*
X267500Y52500D03*
Y47500D03*
Y42500D03*
Y37500D03*
X287500D03*
Y42500D03*
Y47500D03*
Y52500D03*
X309000Y149500D03*
Y164500D03*
Y159500D03*
Y154500D03*
X309131Y193554D03*
Y188554D03*
Y203554D03*
Y198554D03*
X338631Y52054D03*
Y47054D03*
Y42054D03*
Y37054D03*
X329000Y149500D03*
Y154500D03*
Y159500D03*
Y164500D03*
X329131Y188554D03*
Y193554D03*
Y198554D03*
Y203554D03*
X358631Y37054D03*
Y42054D03*
Y47054D03*
Y52054D03*
G54D40*
X318743Y50919D03*
X485348Y106794D03*
G54D13*
X20847Y701602D03*
X32739Y30456D03*
X514356Y57612D03*
G54D23*
X285083Y26528D03*
X332000Y176300D03*
G54D32*
X289800Y150000D03*
X300800D03*
X289800Y158700D03*
X300800D03*
G54D14*
X44685Y19685D03*
Y85039D03*
G54D41*
X322343Y50919D03*
X488948Y106794D03*
G54D33*
X296700Y164800D03*
X519597Y106778D03*
G54D15*
X68112Y15039D03*
Y59528D03*
X233462Y15039D03*
Y59528D03*
X359156Y142992D03*
Y208740D03*
X524506Y142992D03*
Y208740D03*
G54D42*
X484960Y86811D03*
X496771D03*
X508583D03*
X520394D03*
G54D24*
X285083Y29928D03*
X332000Y179700D03*
G54D25*
X281083Y26428D03*
X328034Y176234D03*
G54D34*
X293100Y164800D03*
X515997Y106778D03*
G54D43*
X483520Y101104D03*
X491120D03*
X521558Y101034D03*
X513958D03*
G54D16*
X54724Y24803D03*
Y28740D03*
Y32677D03*
Y36614D03*
Y40551D03*
Y44488D03*
Y48425D03*
Y52362D03*
Y56299D03*
Y60236D03*
Y64173D03*
Y68110D03*
Y72047D03*
Y75984D03*
Y79921D03*
G54D44*
G01X297578Y89882D02*
X303734D01*
G01D02*
X308208D01*
G01X312060Y133300D02*
X315048D01*
G54D26*
X281083Y30028D03*
X328034Y179834D03*
G54D35*
X306460Y32950D03*
X301340D03*
Y39450D03*
X303900D03*
X306460D03*
X317440Y213250D03*
Y219750D03*
X320000D03*
X322560Y213250D03*
Y219750D03*
G54D17*
G01X-139981Y-146685D02*
G02I-12000J0D01*
G01X-145131D02*
G02I-6850J0D01*
G01X-135981D02*
X-167981D01*
G01X-135981Y-162685D02*
Y-242685D01*
G01D02*
X971619D01*
G01X-135981Y-198185D02*
X971619D01*
G01X-151981Y-162685D02*
Y-130685D01*
G01X-135981Y-162685D02*
X971619D01*
G01X76600Y68000D02*
X87000Y78400D01*
X211000D01*
X213100Y80500D01*
Y83500D01*
G01X184119Y-162685D02*
Y-242685D01*
G01X258088Y21787D02*
Y26575D01*
X247263Y37400D01*
X218600D01*
G01X276096Y29819D02*
X276255Y29978D01*
X281083D01*
G01D02*
Y33833D01*
X281221Y33971D01*
G01X285083Y29978D02*
Y32362D01*
X286638Y33917D01*
G01X287500Y52500D02*
X292584D01*
G01D02*
X294816Y54732D01*
X300444D01*
G01X321619Y-162685D02*
Y-242685D01*
G01X315166Y52172D02*
X307544D01*
G01X318793Y50919D02*
X316419D01*
X315166Y52172D01*
G01X323104Y180444D02*
Y181631D01*
X325105Y183632D01*
X326423D01*
G01D02*
X328034Y182021D01*
Y179784D01*
G01X332000Y179750D02*
Y183500D01*
G01X436619Y-162685D02*
Y-242685D01*
G01X496771Y81809D02*
Y86811D01*
G01D02*
Y91813D01*
G01X484960Y81809D02*
Y86811D01*
G01D02*
Y91813D01*
G01X508583Y81809D02*
Y86811D01*
G01D02*
Y91813D01*
G01X520394Y81809D02*
Y86811D01*
G01D02*
Y91813D01*
G01X604119Y-162685D02*
Y-242685D01*
G01X774119Y-162685D02*
Y-242685D01*
G01X971619Y-162685D02*
Y-242685D01*
G01X999619Y-146685D02*
G02I-12000J0D01*
G01X1003619D02*
X971619D01*
G01X994469D02*
G02I-6850J0D01*
G01X987619Y-162685D02*
Y-130685D01*
X60928Y64173D03*
X73567Y4087D03*
X76804Y61699D03*
X76600Y68000D03*
X208000Y90000D03*
X204500D03*
X220310Y4087D03*
X222206Y41500D03*
X218600Y37400D03*
X217880Y83600D03*
X213100Y83500D03*
X268045Y8270D03*
X258088Y21787D03*
X273551Y37112D03*
X293146Y81023D03*
X293141Y97997D03*
X279500Y116900D03*
X279437Y120731D03*
X322100Y26600D03*
X303900Y28900D03*
X313900Y27200D03*
X315166Y52172D03*
X313617Y81023D03*
X321440Y101571D03*
X308208Y101945D03*
X303734Y89882D03*
X309250Y127439D03*
X322042Y147196D03*
X310500Y184328D03*
X340000Y14667D03*
X324700Y16300D03*
X329962Y56703D03*
X337406Y79575D03*
X341133Y80298D03*
X326892Y79371D03*
X338145Y98740D03*
X337670Y90976D03*
X332822Y103140D03*
X327057Y90943D03*
X343028Y87447D03*
X327114Y87334D03*
X340874Y96311D03*
X325404Y101215D03*
X343028Y83447D03*
X327114Y83334D03*
X340874Y92311D03*
X329404Y101215D03*
X336238Y148951D03*
X351040Y34753D03*
X358900Y23928D03*
X345642Y90134D03*
G54D45*
G01X268045Y8270D02*
X278346D01*
X292833Y22757D01*
Y27286D01*
X298497Y32950D01*
X301340D01*
G01X316400Y33000D02*
Y24381D01*
G01X307200Y46300D02*
X306460Y45560D01*
Y39450D01*
G01X318960Y40400D02*
Y48296D01*
X318793Y48463D01*
Y50919D01*
G01X306940Y140700D02*
X303700D01*
G01X317440Y213250D02*
X314454D01*
G01X342560Y20300D02*
X345690D01*
G01X337440Y27700D02*
X332666D01*
G01X326000Y217500D02*
Y218250D01*
X324500Y219750D01*
X322560D01*
G54D36*
X318960Y33000D03*
X316400D03*
X313840D03*
Y40400D03*
X316400D03*
X318960D03*
X306940Y140700D03*
X309500D03*
X312060D03*
Y133300D03*
X309500D03*
X306940D03*
X337440Y27700D03*
X340000D03*
X342560D03*
Y20300D03*
X340000D03*
X337440D03*
G54D27*
X293329Y58557D03*
G54D18*
X93287Y10039D03*
X88287D03*
X93287Y54528D03*
X88287D03*
X118287Y10039D03*
X113287D03*
X108287D03*
X103287D03*
X98287D03*
X118287Y54528D03*
X113287D03*
X108287D03*
X103287D03*
X98287D03*
X163287Y10039D03*
X158287D03*
X153287D03*
X148287D03*
X143287D03*
X163287Y54528D03*
X158287D03*
X153287D03*
X148287D03*
X143287D03*
X183287Y10039D03*
X178287D03*
X173287D03*
X168287D03*
X183287Y54528D03*
X178287D03*
X173287D03*
X168287D03*
X208287Y10039D03*
X203287D03*
X198287D03*
X193287D03*
X188287D03*
X208287Y54528D03*
X203287D03*
X198287D03*
X193287D03*
X188287D03*
X213287Y10039D03*
Y54528D03*
X389331Y137992D03*
X384331D03*
X379331D03*
X389331Y203740D03*
X384331D03*
X379331D03*
X409331Y137992D03*
X404331D03*
X399331D03*
X394331D03*
X409331Y203740D03*
X404331D03*
X399331D03*
X394331D03*
X434331Y137992D03*
Y203740D03*
X459331Y137992D03*
X454331D03*
X449331D03*
X444331D03*
X439331D03*
X459331Y203740D03*
X454331D03*
X449331D03*
X444331D03*
X439331D03*
X479331Y137992D03*
X474331D03*
X469331D03*
X464331D03*
X479331Y203740D03*
X474331D03*
X469331D03*
X464331D03*
X504331Y137992D03*
X499331D03*
X494331D03*
X489331D03*
X484331D03*
X504331Y203740D03*
X499331D03*
X494331D03*
X489331D03*
X484331D03*
G54D46*
G01X-116181Y-215185D02*
Y-232685D01*
G01X-121203Y-215185D02*
X-111159D01*
G01X-103048Y-232685D02*
Y-215185D01*
X-97808D01*
X-96061Y-216060D01*
X-94751Y-218102D01*
X-94314Y-220435D01*
X-94751Y-222768D01*
X-95843Y-224518D01*
X-97808Y-225394D01*
X-103048D01*
G01X-58878Y-216644D02*
X-60188Y-215768D01*
X-61716Y-215185D01*
X-63463D01*
X-65428Y-216060D01*
X-66956Y-217518D01*
X-68048Y-219269D01*
X-68921Y-222185D01*
X-69140Y-224810D01*
X-68703Y-227435D01*
X-68048Y-229185D01*
X-66738Y-230935D01*
X-65209Y-232102D01*
X-63681Y-232685D01*
X-62153D01*
X-60624Y-232102D01*
X-59314Y-231227D01*
X-58222Y-230061D01*
G01X-49893Y-232685D02*
Y-215185D01*
G01Y-223643D02*
X-48801Y-222185D01*
X-47709Y-221310D01*
X-45963Y-221019D01*
X-44653Y-221310D01*
X-43124Y-222477D01*
X-42469Y-224227D01*
Y-232685D01*
G01X-24751D02*
Y-221019D01*
G01Y-223060D02*
X-25624Y-221894D01*
X-26935Y-221310D01*
X-28463Y-221019D01*
X-29991Y-221602D01*
X-31301Y-222768D01*
X-32175Y-224518D01*
X-32611Y-226852D01*
X-32175Y-229185D01*
X-31301Y-230935D01*
X-29991Y-232102D01*
X-28463Y-232685D01*
X-26935Y-232393D01*
X-25624Y-231519D01*
X-24751Y-230352D01*
G01X-14893Y-232685D02*
Y-221019D01*
G01Y-223935D02*
X-14019Y-222477D01*
X-12709Y-221310D01*
X-10963Y-221019D01*
X-9435Y-221310D01*
X-8124Y-222477D01*
X-7469Y-224518D01*
Y-232685D01*
G01X2607D02*
Y-221019D01*
G01Y-223935D02*
X3481Y-222477D01*
X4791Y-221310D01*
X6537Y-221019D01*
X8065Y-221310D01*
X9376Y-222477D01*
X10031Y-224518D01*
Y-232685D01*
G01X20544Y-224810D02*
X27531D01*
X26876Y-222768D01*
X25784Y-221602D01*
X24256Y-221019D01*
X22727Y-221310D01*
X21417Y-222185D01*
X20544Y-224227D01*
X20107Y-225977D01*
Y-227727D01*
X20544Y-229477D01*
X21636Y-231227D01*
X22946Y-232393D01*
X24474Y-232685D01*
X26002Y-232102D01*
X27531Y-230352D01*
G01X41319Y-232685D02*
Y-215185D01*
G01X71734Y-232685D02*
Y-215185D01*
G01X80904D02*
Y-232685D01*
G01Y-223935D02*
X71734D01*
G01X89016Y-232685D02*
Y-215185D01*
X93382D01*
X95129Y-216060D01*
X96439Y-217227D01*
X97531Y-218976D01*
X98404Y-221019D01*
X98622Y-223935D01*
X98404Y-226852D01*
X97531Y-228894D01*
X96439Y-230644D01*
X95129Y-231810D01*
X93382Y-232685D01*
X89016D01*
G01X106516D02*
Y-215185D01*
X110882D01*
X112629Y-216060D01*
X113939Y-217227D01*
X115031Y-218976D01*
X115904Y-221019D01*
X116122Y-223935D01*
X115904Y-226852D01*
X115031Y-228894D01*
X113939Y-230644D01*
X112629Y-231810D01*
X110882Y-232685D01*
X106516D01*
G01X148065Y-223352D02*
X148939Y-222477D01*
X149594Y-221019D01*
X150031Y-218976D01*
X149594Y-217227D01*
X148721Y-216060D01*
X147192Y-215185D01*
X141297D01*
Y-232685D01*
X148502D01*
X150031Y-231519D01*
X150904Y-229768D01*
X151341Y-227727D01*
X150904Y-225685D01*
X149594Y-223935D01*
X148065Y-223352D01*
X141297D01*
G01X159452Y-232685D02*
Y-215185D01*
X164692D01*
X166439Y-216060D01*
X167749Y-218102D01*
X168186Y-220435D01*
X167749Y-222768D01*
X166657Y-224518D01*
X164692Y-225394D01*
X159452D01*
G01X-16858Y-187685D02*
Y-170185D01*
X-11181Y-184768D01*
X-5504Y-170185D01*
Y-187685D01*
G01X6319D02*
X5009Y-187393D01*
X3699Y-186227D01*
X2825Y-184185D01*
X2389Y-181852D01*
X2825Y-179518D01*
X3699Y-177477D01*
X5009Y-176310D01*
X6319Y-176019D01*
X7629Y-176310D01*
X8939Y-177477D01*
X9812Y-179518D01*
X10031Y-181852D01*
X9812Y-184185D01*
X8939Y-186227D01*
X7629Y-187393D01*
X6319Y-187685D01*
G01X27749Y-170185D02*
Y-187685D01*
G01Y-185061D02*
X26876Y-186519D01*
X25565Y-187393D01*
X24037Y-187685D01*
X22291Y-187102D01*
X20981Y-185644D01*
X20107Y-183894D01*
X19889Y-181852D01*
X20107Y-179810D01*
X20981Y-178060D01*
X22291Y-176602D01*
X24037Y-176019D01*
X25565Y-176310D01*
X26657Y-176894D01*
X27749Y-178060D01*
G01X38044Y-179810D02*
X45031D01*
X44376Y-177768D01*
X43284Y-176602D01*
X41756Y-176019D01*
X40227Y-176310D01*
X38917Y-177185D01*
X38044Y-179227D01*
X37607Y-180977D01*
Y-182727D01*
X38044Y-184477D01*
X39136Y-186227D01*
X40446Y-187393D01*
X41974Y-187685D01*
X43502Y-187102D01*
X45031Y-185352D01*
G01X58819Y-187685D02*
Y-170185D01*
G01X204702Y-187685D02*
Y-170185D01*
X209942D01*
X211689Y-171060D01*
X212999Y-173102D01*
X213436Y-175435D01*
X212999Y-177768D01*
X211907Y-179518D01*
X209942Y-180394D01*
X204702D01*
G01X231372Y-171644D02*
X230062Y-170768D01*
X228534Y-170185D01*
X226787D01*
X224822Y-171060D01*
X223294Y-172518D01*
X222202Y-174269D01*
X221329Y-177185D01*
X221110Y-179810D01*
X221547Y-182435D01*
X222202Y-184185D01*
X223512Y-185935D01*
X225041Y-187102D01*
X226569Y-187685D01*
X228097D01*
X229626Y-187102D01*
X230936Y-186227D01*
X232028Y-185061D01*
G01X245815Y-178352D02*
X246689Y-177477D01*
X247344Y-176019D01*
X247781Y-173976D01*
X247344Y-172227D01*
X246471Y-171060D01*
X244942Y-170185D01*
X239047D01*
Y-187685D01*
X246252D01*
X247781Y-186519D01*
X248654Y-184768D01*
X249091Y-182727D01*
X248654Y-180685D01*
X247344Y-178935D01*
X245815Y-178352D01*
X239047D01*
G01X255019Y-193518D02*
X268119D01*
G01X274047Y-187685D02*
Y-170185D01*
X284091Y-187685D01*
Y-170185D01*
G01X296569Y-187685D02*
X294822Y-187393D01*
X293294Y-186227D01*
X291984Y-184477D01*
X291110Y-182435D01*
X290674Y-180102D01*
Y-177768D01*
X291110Y-175435D01*
X291984Y-173393D01*
X293294Y-171644D01*
X294822Y-170477D01*
X296569Y-170185D01*
X298315Y-170477D01*
X299844Y-171644D01*
X301154Y-173393D01*
X302028Y-175435D01*
X302464Y-177768D01*
Y-180102D01*
X302028Y-182435D01*
X301154Y-184477D01*
X299844Y-186227D01*
X298315Y-187393D01*
X296569Y-187685D01*
G01X217819Y-232685D02*
Y-215185D01*
X215199Y-218685D01*
G01Y-232685D02*
X220439D01*
G01X234882D02*
X235319Y-228894D01*
X235974Y-225685D01*
X236847Y-222768D01*
X237939Y-219560D01*
X239686Y-215185D01*
X230952D01*
G01X248016Y-229185D02*
X249325Y-231227D01*
X251072Y-232393D01*
X253037Y-232685D01*
X254784Y-232393D01*
X256531Y-230935D01*
X257622Y-229185D01*
X257841Y-227435D01*
X257404Y-225394D01*
X255876Y-223935D01*
X254347Y-223352D01*
X252382D01*
G01X254347D02*
X255657Y-222477D01*
X256749Y-221019D01*
X257186Y-219269D01*
X256749Y-217518D01*
X255657Y-216060D01*
X253692Y-215185D01*
X251727Y-215477D01*
X249762Y-216644D01*
G01X270319Y-215185D02*
X268572Y-215768D01*
X267262Y-217227D01*
X266389Y-218976D01*
X265734Y-221310D01*
X265516Y-223935D01*
X265734Y-226560D01*
X266389Y-228894D01*
X267262Y-230644D01*
X268572Y-232102D01*
X270319Y-232685D01*
X272065Y-232102D01*
X273376Y-230644D01*
X274249Y-228894D01*
X274904Y-226560D01*
X275122Y-223935D01*
X274904Y-221310D01*
X274249Y-218976D01*
X273376Y-217227D01*
X272065Y-215768D01*
X270319Y-215185D01*
G01X287819Y-232685D02*
Y-215185D01*
X285199Y-218685D01*
G01Y-232685D02*
X290439D01*
G01X365784Y-230352D02*
X367531Y-231810D01*
X369496Y-232685D01*
X371242D01*
X372989Y-231810D01*
X374299Y-230352D01*
X374954Y-228310D01*
X374517Y-226269D01*
X373426Y-224518D01*
X371461Y-223352D01*
X368841Y-222768D01*
X367312Y-221602D01*
X366657Y-219560D01*
X367094Y-217518D01*
X368186Y-216060D01*
X369714Y-215185D01*
X371242D01*
X372771Y-215768D01*
X374081Y-217227D01*
G01X382410Y-232685D02*
X387869Y-215185D01*
X393328Y-232685D01*
G01X391362Y-226560D02*
X384375D01*
G01X347410Y-170185D02*
X352869Y-187685D01*
X358328Y-170185D01*
G01X374736Y-187685D02*
X366002D01*
Y-170185D01*
X374736D01*
G01X371242Y-178643D02*
X366002D01*
G01X383502Y-187685D02*
Y-170185D01*
X388961D01*
X390707Y-171060D01*
X391799Y-172227D01*
X392236Y-174560D01*
X391799Y-176894D01*
X390489Y-178352D01*
X388961Y-179227D01*
X383502D01*
G01X388961D02*
X392236Y-187685D01*
G01X405369Y-188268D02*
X404932Y-187977D01*
Y-187393D01*
X405369Y-187102D01*
X405806Y-187393D01*
Y-187977D01*
X405369Y-188268D01*
G01X480952Y-170185D02*
Y-187685D01*
X489686D01*
G01X506749D02*
Y-176019D01*
G01Y-178060D02*
X505876Y-176894D01*
X504565Y-176310D01*
X503037Y-176019D01*
X501509Y-176602D01*
X500199Y-177768D01*
X499325Y-179518D01*
X498889Y-181852D01*
X499325Y-184185D01*
X500199Y-185935D01*
X501509Y-187102D01*
X503037Y-187685D01*
X504565Y-187393D01*
X505876Y-186519D01*
X506749Y-185352D01*
G01X515734Y-192935D02*
X517044Y-193518D01*
X518791Y-192935D01*
X519882Y-191769D01*
X520756Y-190310D01*
X522065Y-185644D01*
X524904Y-176019D01*
G01X517917D02*
X522065Y-185644D01*
G01X534544Y-179810D02*
X541531D01*
X540876Y-177768D01*
X539784Y-176602D01*
X538256Y-176019D01*
X536727Y-176310D01*
X535417Y-177185D01*
X534544Y-179227D01*
X534107Y-180977D01*
Y-182727D01*
X534544Y-184477D01*
X535636Y-186227D01*
X536946Y-187393D01*
X538474Y-187685D01*
X540002Y-187102D01*
X541531Y-185352D01*
G01X552262Y-187685D02*
Y-176019D01*
G01Y-178352D02*
X553354Y-177185D01*
X554446Y-176310D01*
X555974Y-176019D01*
X557065Y-176310D01*
X558376Y-177185D01*
G01X533436Y-215185D02*
Y-232685D01*
X524702D01*
G01X515717Y-225394D02*
X514189Y-223352D01*
X512879Y-222185D01*
X511132Y-221602D01*
X509604Y-222185D01*
X508512Y-223352D01*
X507639Y-225102D01*
X507421Y-227143D01*
X507639Y-228894D01*
X508512Y-230644D01*
X509823Y-232102D01*
X511351Y-232685D01*
X513097Y-232102D01*
X514626Y-230352D01*
X515499Y-227727D01*
X515717Y-224810D01*
X515281Y-221019D01*
X514626Y-218976D01*
X513534Y-216935D01*
X512006Y-215477D01*
X510477Y-215185D01*
X508949Y-215768D01*
X507857Y-217227D01*
G01X623066Y-187685D02*
Y-170185D01*
X627432D01*
X629179Y-171060D01*
X630489Y-172227D01*
X631581Y-173976D01*
X632454Y-176019D01*
X632672Y-178935D01*
X632454Y-181852D01*
X631581Y-183894D01*
X630489Y-185644D01*
X629179Y-186810D01*
X627432Y-187685D01*
X623066D01*
G01X642094Y-179810D02*
X649081D01*
X648426Y-177768D01*
X647334Y-176602D01*
X645806Y-176019D01*
X644277Y-176310D01*
X642967Y-177185D01*
X642094Y-179227D01*
X641657Y-180977D01*
Y-182727D01*
X642094Y-184477D01*
X643186Y-186227D01*
X644496Y-187393D01*
X646024Y-187685D01*
X647552Y-187102D01*
X649081Y-185352D01*
G01X659594Y-185644D02*
X660686Y-186810D01*
X662214Y-187685D01*
X663524D01*
X664834Y-187102D01*
X665707Y-186227D01*
X666144Y-185061D01*
X665926Y-183310D01*
X665052Y-182435D01*
X661122Y-180685D01*
X660249Y-178643D01*
X660686Y-177185D01*
X661559Y-176310D01*
X662869Y-176019D01*
X664179Y-176310D01*
X665489Y-177185D01*
G01X680369Y-176019D02*
Y-187685D01*
G01Y-171352D02*
X679932Y-171060D01*
Y-170477D01*
X680369Y-170185D01*
X680806Y-170477D01*
Y-171060D01*
X680369Y-171352D01*
G01X694812Y-192060D02*
X696341Y-193227D01*
X698087Y-193518D01*
X699615Y-193227D01*
X700926Y-191769D01*
X701799Y-189727D01*
Y-176019D01*
G01Y-178352D02*
X700926Y-177185D01*
X699615Y-176310D01*
X698087Y-176019D01*
X696341Y-176602D01*
X695249Y-177768D01*
X694375Y-179810D01*
X693939Y-181852D01*
X694157Y-183602D01*
X695031Y-185644D01*
X696341Y-187102D01*
X698087Y-187685D01*
X699397Y-187393D01*
X700926Y-186227D01*
X701799Y-185061D01*
G01X711657Y-187685D02*
Y-176019D01*
G01Y-178935D02*
X712531Y-177477D01*
X713841Y-176310D01*
X715587Y-176019D01*
X717115Y-176310D01*
X718426Y-177477D01*
X719081Y-179518D01*
Y-187685D01*
G01X729594Y-179810D02*
X736581D01*
X735926Y-177768D01*
X734834Y-176602D01*
X733306Y-176019D01*
X731777Y-176310D01*
X730467Y-177185D01*
X729594Y-179227D01*
X729157Y-180977D01*
Y-182727D01*
X729594Y-184477D01*
X730686Y-186227D01*
X731996Y-187393D01*
X733524Y-187685D01*
X735052Y-187102D01*
X736581Y-185352D01*
G01X747312Y-187685D02*
Y-176019D01*
G01Y-178352D02*
X748404Y-177185D01*
X749496Y-176310D01*
X751024Y-176019D01*
X752115Y-176310D01*
X753426Y-177185D01*
G01X664179Y-223935D02*
X668546D01*
Y-229185D01*
X667236Y-230935D01*
X665707Y-232102D01*
X663524Y-232685D01*
X661341Y-232102D01*
X659812Y-230935D01*
X658502Y-229185D01*
X657629Y-227143D01*
X657192Y-224810D01*
Y-222768D01*
X657629Y-221019D01*
X658502Y-218976D01*
X659812Y-217227D01*
X661122Y-216060D01*
X662869Y-215185D01*
X664397D01*
X666144Y-215768D01*
X667454Y-216935D01*
G01X684736Y-232685D02*
X676002D01*
Y-215185D01*
X684736D01*
G01X681242Y-223643D02*
X676002D01*
G01X693502Y-215185D02*
Y-232685D01*
X702236D01*
G01X715369D02*
X713622Y-232393D01*
X712094Y-231227D01*
X710784Y-229477D01*
X709910Y-227435D01*
X709474Y-225102D01*
Y-222768D01*
X709910Y-220435D01*
X710784Y-218393D01*
X712094Y-216644D01*
X713622Y-215477D01*
X715369Y-215185D01*
X717115Y-215477D01*
X718644Y-216644D01*
X719954Y-218393D01*
X720828Y-220435D01*
X721264Y-222768D01*
Y-225102D01*
X720828Y-227435D01*
X719954Y-229477D01*
X718644Y-231227D01*
X717115Y-232393D01*
X715369Y-232685D01*
G01X794069Y-215185D02*
X792322Y-215768D01*
X791012Y-217227D01*
X790139Y-218976D01*
X789484Y-221310D01*
X789266Y-223935D01*
X789484Y-226560D01*
X790139Y-228894D01*
X791012Y-230644D01*
X792322Y-232102D01*
X794069Y-232685D01*
X795815Y-232102D01*
X797126Y-230644D01*
X797999Y-228894D01*
X798654Y-226560D01*
X798872Y-223935D01*
X798654Y-221310D01*
X797999Y-218976D01*
X797126Y-217227D01*
X795815Y-215768D01*
X794069Y-215185D01*
G01X807421Y-225394D02*
X808949Y-223352D01*
X810259Y-222185D01*
X812006Y-221602D01*
X813534Y-222185D01*
X814626Y-223352D01*
X815499Y-225102D01*
X815717Y-227143D01*
X815499Y-228894D01*
X814626Y-230644D01*
X813315Y-232102D01*
X811787Y-232685D01*
X810041Y-232102D01*
X808512Y-230352D01*
X807639Y-227727D01*
X807421Y-224810D01*
X807857Y-221019D01*
X808512Y-218976D01*
X809604Y-216935D01*
X811132Y-215477D01*
X812661Y-215185D01*
X814189Y-215768D01*
X815281Y-217227D01*
G01X825139Y-233268D02*
X832999Y-215185D01*
G01X842421Y-218102D02*
X843731Y-216352D01*
X845259Y-215477D01*
X847006Y-215185D01*
X849189Y-215768D01*
X850717Y-217227D01*
X851154Y-218976D01*
X850936Y-220727D01*
X850062Y-222185D01*
X845696Y-225102D01*
X843731Y-227143D01*
X842421Y-230061D01*
X841984Y-232685D01*
X851154D01*
G01X859921Y-218102D02*
X861231Y-216352D01*
X862759Y-215477D01*
X864506Y-215185D01*
X866689Y-215768D01*
X868217Y-217227D01*
X868654Y-218976D01*
X868436Y-220727D01*
X867562Y-222185D01*
X863196Y-225102D01*
X861231Y-227143D01*
X859921Y-230061D01*
X859484Y-232685D01*
X868654D01*
G01X877639Y-233268D02*
X885499Y-215185D01*
G01X894921Y-218102D02*
X896231Y-216352D01*
X897759Y-215477D01*
X899506Y-215185D01*
X901689Y-215768D01*
X903217Y-217227D01*
X903654Y-218976D01*
X903436Y-220727D01*
X902562Y-222185D01*
X898196Y-225102D01*
X896231Y-227143D01*
X894921Y-230061D01*
X894484Y-232685D01*
X903654D01*
G01X916569Y-215185D02*
X914822Y-215768D01*
X913512Y-217227D01*
X912639Y-218976D01*
X911984Y-221310D01*
X911766Y-223935D01*
X911984Y-226560D01*
X912639Y-228894D01*
X913512Y-230644D01*
X914822Y-232102D01*
X916569Y-232685D01*
X918315Y-232102D01*
X919626Y-230644D01*
X920499Y-228894D01*
X921154Y-226560D01*
X921372Y-223935D01*
X921154Y-221310D01*
X920499Y-218976D01*
X919626Y-217227D01*
X918315Y-215768D01*
X916569Y-215185D01*
G01X934069Y-232685D02*
Y-215185D01*
X931449Y-218685D01*
G01Y-232685D02*
X936689D01*
G01X951132D02*
X951569Y-228894D01*
X952224Y-225685D01*
X953097Y-222768D01*
X954189Y-219560D01*
X955936Y-215185D01*
X947202D01*
G01X841766Y-187685D02*
Y-170185D01*
X846132D01*
X847879Y-171060D01*
X849189Y-172227D01*
X850281Y-173976D01*
X851154Y-176019D01*
X851372Y-178935D01*
X851154Y-181852D01*
X850281Y-183894D01*
X849189Y-185644D01*
X847879Y-186810D01*
X846132Y-187685D01*
X841766D01*
G01X867999D02*
Y-176019D01*
G01Y-178060D02*
X867126Y-176894D01*
X865815Y-176310D01*
X864287Y-176019D01*
X862759Y-176602D01*
X861449Y-177768D01*
X860575Y-179518D01*
X860139Y-181852D01*
X860575Y-184185D01*
X861449Y-185935D01*
X862759Y-187102D01*
X864287Y-187685D01*
X865815Y-187393D01*
X867126Y-186519D01*
X867999Y-185352D01*
G01X881569Y-170185D02*
Y-187685D01*
G01X878512Y-176019D02*
X884626D01*
G01X895794Y-179810D02*
X902781D01*
X902126Y-177768D01*
X901034Y-176602D01*
X899506Y-176019D01*
X897977Y-176310D01*
X896667Y-177185D01*
X895794Y-179227D01*
X895357Y-180977D01*
Y-182727D01*
X895794Y-184477D01*
X896886Y-186227D01*
X898196Y-187393D01*
X899724Y-187685D01*
X901252Y-187102D01*
X902781Y-185352D01*
G54D37*
X307400Y46300D03*
G54D28*
X287729Y58557D03*
G54D19*
X75100Y36700D03*
X74635Y29153D03*
X261939Y10864D03*
X261403Y18848D03*
X292129Y215485D03*
X288498Y207172D03*
X328196Y32237D03*
X337494Y177470D03*
X331841Y233317D03*
X470551Y112318D03*
X459514Y113175D03*
X506868Y166599D03*
X547629Y215319D03*
X549807Y89951D03*
G54D47*
G01X322100Y26600D02*
Y32280D01*
X321380Y33000D01*
X318960D01*
G01X303900Y28900D02*
X306460Y31460D01*
Y32950D01*
G01X313900Y27200D02*
X313840Y27260D01*
Y33000D01*
G54D29*
X300444Y54732D03*
X307544Y57292D03*
Y52172D03*
G54D38*
X313000Y46300D03*
G54D48*
G01X108287Y10039D02*
X110046Y11798D01*
Y13815D01*
X111739Y15888D01*
X120749Y17721D01*
X131189Y15597D01*
X170994Y23696D01*
X201984Y44207D01*
X236393Y51211D01*
X285135Y83472D01*
X292121Y94026D01*
X293769Y95181D01*
X295384D01*
X295990Y95787D01*
X297578D01*
G01X113287Y10039D02*
X111786Y11540D01*
Y13194D01*
X112695Y14306D01*
X116723Y15126D01*
X116722D01*
X120749Y15945D01*
X131189Y13821D01*
X133658Y14322D01*
Y14323D01*
X134720Y13621D01*
X137189Y14123D01*
X137892Y15185D01*
X140361Y15687D01*
X141423Y14985D01*
X143892Y15487D01*
X144595Y16549D01*
X147064Y17051D01*
X148126Y16349D01*
X150595Y16851D01*
X151298Y17913D01*
X153767Y18415D01*
X154829Y17713D01*
X157298Y18215D01*
X158000Y19276D01*
X171672Y22058D01*
X202662Y42569D01*
X237071Y49573D01*
X286391Y82216D01*
X293391Y92790D01*
Y92791D01*
X294318Y93440D01*
Y93441D01*
X295470D01*
X296076Y92835D01*
X297578D01*
G01X108287Y54528D02*
X109917Y56158D01*
Y58069D01*
X111404Y60308D01*
X123676Y62805D01*
X135582Y60383D01*
X184311Y70297D01*
X211996Y64666D01*
X250023Y72403D01*
X281646Y93331D01*
X285136Y98603D01*
X291054Y102747D01*
X297896Y104139D01*
X301497Y101757D01*
X301643Y101661D01*
X304271Y99033D01*
Y95866D01*
X305111Y95026D01*
X306065D01*
X306826Y95787D01*
X308208D01*
G01X113287Y54528D02*
X111657Y56158D01*
Y57543D01*
X112456Y58746D01*
X123676Y61029D01*
X135582Y58607D01*
X138051Y59109D01*
X139113Y58407D01*
X141582Y58909D01*
X142285Y59971D01*
X144754Y60473D01*
X145816Y59771D01*
X148285Y60273D01*
X148988Y61335D01*
X151457Y61837D01*
X152519Y61135D01*
X154988Y61637D01*
X155691Y62699D01*
X158160Y63201D01*
X159222Y62499D01*
X161691Y63001D01*
X162394Y64062D01*
X184311Y68521D01*
X211996Y62890D01*
X250701Y70765D01*
X282902Y92075D01*
X286405Y97367D01*
X291756Y101114D01*
X297537Y102290D01*
X300539Y100304D01*
X302531Y98312D01*
Y95145D01*
X304390Y93286D01*
X306339D01*
X306790Y92835D01*
X308208D01*
G01X399331Y137992D02*
X400970Y136353D01*
Y135098D01*
X400304Y131826D01*
X398658Y129341D01*
X383230Y119128D01*
X383229Y119129D01*
X367804Y108918D01*
X363528Y102458D01*
X362280Y102204D01*
X360889Y100103D01*
X361143Y98855D01*
X359752Y96754D01*
X358505Y96500D01*
X357114Y94399D01*
X357368Y93151D01*
X355977Y91050D01*
X354730Y90796D01*
X353339Y88695D01*
X353593Y87447D01*
X352202Y85346D01*
X350955Y85092D01*
X349564Y82991D01*
X349818Y81743D01*
X348427Y79642D01*
X340132Y74011D01*
X331809Y72318D01*
X326866Y73324D01*
X318659Y71654D01*
X313229Y72759D01*
X307202Y71532D01*
X304306Y73451D01*
X303426Y77770D01*
Y84669D01*
X301567Y86528D01*
X299664D01*
X299263Y86929D01*
X297578D01*
G01X404331Y137992D02*
X402710Y136371D01*
Y134922D01*
X401942Y131148D01*
X399914Y128085D01*
X369060Y107662D01*
X349689Y78395D01*
X340821Y72375D01*
X331809Y70542D01*
X326866Y71548D01*
X318659Y69878D01*
X313229Y70983D01*
X306842Y69683D01*
X302744Y72397D01*
X301686Y77594D01*
Y83948D01*
X300846Y84788D01*
X299844D01*
X299032Y83976D01*
X297578D01*
G01X399331Y203740D02*
X400961Y202110D01*
Y200266D01*
X398715Y196873D01*
X396246Y196371D01*
X395184Y197073D01*
X392715Y196571D01*
X392012Y195509D01*
X389543Y195007D01*
X388481Y195709D01*
X386012Y195207D01*
X385309Y194146D01*
X379796Y193024D01*
X373082Y188581D01*
X323618Y113848D01*
X322371Y113594D01*
X320980Y111493D01*
X321234Y110245D01*
X319843Y108144D01*
X318596Y107890D01*
X317205Y105789D01*
X317459Y104541D01*
X316068Y102440D01*
X314451Y94494D01*
X315614Y88775D01*
X314220Y86668D01*
X312421Y86302D01*
X310859D01*
X310232Y86929D01*
X308208D01*
G01X404331Y203740D02*
X402701Y202110D01*
Y199741D01*
X399769Y195311D01*
X380474Y191386D01*
X374338Y187325D01*
X317706Y101762D01*
X316227Y94494D01*
X317463Y88416D01*
X315274Y85106D01*
X312597Y84562D01*
X310791D01*
X310205Y83976D01*
X308208D01*
G01X343028Y87447D02*
X341898Y86317D01*
X335308D01*
X334696Y86929D01*
X332736D01*
G01X327114Y87334D02*
X325984Y86204D01*
X324557D01*
X323832Y86929D01*
X322106D01*
G01X340874Y96311D02*
X339744Y95181D01*
X335028D01*
X334422Y95787D01*
X332736D01*
G01X325404Y101215D02*
X326534Y100085D01*
Y96133D01*
X325694Y95293D01*
X324506D01*
X324012Y95787D01*
X322106D01*
G01X343028Y83447D02*
X341898Y84577D01*
X334983D01*
X334382Y83976D01*
X332736D01*
G01X327114Y83334D02*
X325984Y84464D01*
X324383D01*
X323895Y83976D01*
X322106D01*
G01X340874Y92311D02*
X339744Y93441D01*
X335112D01*
X334506Y92835D01*
X332736D01*
G01X329404Y101215D02*
X328274Y100085D01*
Y95412D01*
X326415Y93553D01*
X324484D01*
X323766Y92835D01*
X322106D01*
G54D39*
X316624Y56703D03*
X319400Y141500D03*
X325624Y56703D03*
X328400Y141500D03*
X349900Y29400D03*
X358900D03*
M02*
